# TIMECARD (Time Appliance Project (Time Card)) — schematic netlist excerpt (pin names and nets, part order shuffled) for the footprints in the layout excerpt that follows; sources: Cadence DE-HDL packaged netlist, KiCad conversion of R4006-B0001-02_R01.brd

C182  CAPACITOR  0.1UF 25V 10%  pkg SMC_0402R_H022  page 30 : \1\ = XP3R3V ; \2\ = SG
C227  CAPACITOR  0.1UF 25V 10%  pkg SMC_0402R_H022  page 31 : \1\ = UNNAMED_515_CAPACITOR_I128_1 ; \2\ = SG
TP50  TP_PIONT  pkg TP010CT020B030_PTH  page 25 : \1\ = CLK_125M_OE

(kicad_pcb
	(version 20260206)
	(generator "pcbnew")
	(generator_version "10.0")
	(general
		(thickness 1.6)
		(legacy_teardrops no)
	)
	(paper "A4")
	(title_block
		(title "timecard-production-celestica-r4006 — R4006-B0001-02_R01.brd")
		(comment 1 "Time Appliance Project (Time Card) / footprints 670-672 of 1113")
	)
	(layers
		(0 "F.Cu" signal "TOP")
		(4 "In1.Cu" signal "L02_GND1")
		(6 "In2.Cu" signal "L03_SIG1")
		(8 "In3.Cu" signal "L04_GND2")
		(10 "In4.Cu" signal "L05_VCC1")
		(12 "In5.Cu" signal "L06_VCC2")
		(14 "In6.Cu" signal "L07_GND3")
		(16 "In7.Cu" signal "L08_SIG2")
		(18 "In8.Cu" signal "L09_GND4")
		(2 "B.Cu" signal "BOTTOM")
		(9 "F.Adhes" user "F.Adhesive")
		(11 "B.Adhes" user "B.Adhesive")
		(13 "F.Paste" user "Package Geometry/Pastemask Top")
		(15 "B.Paste" user "Package Geometry/Pastemask Bottom")
		(5 "F.SilkS" user "Ref Des/Silkscreen Top")
		(7 "B.SilkS" user "Ref Des/Silkscreen Bottom")
		(1 "F.Mask" user "Board Geometry/Soldermask Top")
		(3 "B.Mask" user "Board Geometry/Soldermask Bottom")
		(17 "Dwgs.User" user "User.Drawings")
		(19 "Cmts.User" user "User.Comments")
		(21 "Eco1.User" user "User.Eco1")
		(23 "Eco2.User" user "User.Eco2")
		(25 "Edge.Cuts" user "Board Geometry/Outline")
		(27 "Margin" user)
		(31 "F.CrtYd" user "Package Geometry/Place Bound Top")
		(29 "B.CrtYd" user "Package Geometry/Place Bound Bottom")
		(35 "F.Fab" user "Ref Des/Assembly Top")
		(33 "B.Fab" user "Ref Des/Assembly Bottom")
	)
	(footprint ""
		(layer "F.Cu")
		(at 93.0148 -76.1238 -90)
		(property "Reference" "C182"
			(at -18.9992 27.06243 90)
			(unlocked yes)
			(layer "F.SilkS")
			(effects
				(font
					(size 0.7874 0.5842)
					(thickness 0.1524)
				)
			)
		)
		(property "Value" "VAL*"
			(at 0.0762 2.067306 270)
			(unlocked yes)
			(layer "F.Fab")
			(hide yes)
			(effects
				(font
					(size 0.7874 0.5842)
					(thickness 0.1524)
				)
			)
		)
		(property "Tolerance" "TOL*"
			(at 0.0762 3.032506 270)
			(unlocked yes)
			(layer "Cmts.User")
			(hide yes)
			(effects
				(font
					(size 0.7874 0.5842)
					(thickness 0.1524)
				)
			)
		)
		(property "User Part Number" "PARTNUM*"
			(at 0.1016 4.023106 270)
			(unlocked yes)
			(layer "Cmts.User")
			(hide yes)
			(effects
				(font
					(size 0.7874 0.5842)
					(thickness 0.1524)
				)
			)
		)
		(property "Device Type" "CAPACITOR-G105-0B104-EK,0.1UF,A"
			(at 0.0508 1.127506 270)
			(unlocked yes)
			(layer "F.Fab")
			(hide yes)
			(effects
				(font
					(size 0.7874 0.5842)
					(thickness 0.1524)
				)
			)
		)
		(duplicate_pad_numbers_are_jumpers no)
		(fp_line
			(start -1.143 0.5588)
			(end 1.143 0.5588)
			(stroke
				(width 0.1)
				(type default)
			)
			(layer "F.SilkS")
		)
		(fp_line
			(start 1.143 0.5588)
			(end 1.143 -0.5588)
			(stroke
				(width 0.1)
				(type default)
			)
			(layer "F.SilkS")
		)
		(fp_line
			(start -1.143 -0.5588)
			(end -1.143 0.5588)
			(stroke
				(width 0.1)
				(type default)
			)
			(layer "F.SilkS")
		)
		(fp_line
			(start 1.143 -0.5588)
			(end -1.143 -0.5588)
			(stroke
				(width 0.1)
				(type default)
			)
			(layer "F.SilkS")
		)
		(fp_rect
			(start -1.143 0.5588)
			(end 1.143 -0.5588)
			(stroke
				(width 0)
				(type default)
			)
			(fill no)
			(layer "F.CrtYd")
		)
		(fp_line
			(start -0.508 0.3048)
			(end 0.508 0.3048)
			(stroke
				(width 0.1)
				(type default)
			)
			(layer "F.Fab")
		)
		(fp_line
			(start 0.508 0.3048)
			(end 0.508 -0.3048)
			(stroke
				(width 0.1)
				(type default)
			)
			(layer "F.Fab")
		)
		(fp_line
			(start -0.508 -0.3048)
			(end -0.508 0.3048)
			(stroke
				(width 0.1)
				(type default)
			)
			(layer "F.Fab")
		)
		(fp_line
			(start 0.508 -0.3048)
			(end -0.508 -0.3048)
			(stroke
				(width 0.1)
				(type default)
			)
			(layer "F.Fab")
		)
		(pad "1" smd rect
			(at -0.5334 0 270)
			(size 0.7112 0.6096)
			(layers "F.Cu" "F.Mask" "F.Paste")
			(net "XP3R3V")
		)
		(pad "2" smd rect
			(at 0.5334 0 270)
			(size 0.7112 0.6096)
			(layers "F.Cu" "F.Mask" "F.Paste")
			(net "SG")
		)
		(zone
			(layer "F.Cu")
			(hatch none 0.5)
			(connect_pads
				(clearance 0)
			)
			(min_thickness 0.25)
			(keepout
				(tracks allowed)
				(vias not_allowed)
				(pads allowed)
				(copperpour not_allowed)
				(footprints allowed)
			)
			(placement
				(enabled no)
				(sheetname "")
			)
			(fill
				(thermal_gap 0.5)
				(thermal_bridge_width 0.5)
				(island_removal_mode 0)
			)
			(polygon
				(pts
					(xy 92.71 -76.2) (xy 92.71 -76.0476) (xy 93.3196 -76.0476) (xy 93.3196 -76.2)
				)
			)
		)
	)
	(footprint ""
		(layer "F.Cu")
		(at 94.107 -21.336)
		(property "Reference" "TP50"
			(at -2.3622 1.43637 0)
			(unlocked yes)
			(layer "F.SilkS")
			(effects
				(font
					(size 0.7874 0.5842)
					(thickness 0.1524)
				)
				(justify left)
			)
		)
		(property "Value" ""
			(at 0 0 0)
			(layer "F.Fab")
			(effects
				(font
					(size 1.27 1.27)
				)
			)
		)
		(property "Device Type" "TP_PIONT-TP010CT020B030_PTH-TPA"
			(at -1.341882 0.996696 0)
			(unlocked yes)
			(layer "F.Fab")
			(hide yes)
			(effects
				(font
					(size 0.7874 0.5842)
					(thickness 0.000001)
				)
				(justify left)
			)
		)
		(duplicate_pad_numbers_are_jumpers no)
		(fp_poly
			(pts
				(arc
					(start 0.889 0)
					(mid -0.889 0)
					(end 0.889 0)
				)
			)
			(stroke
				(width 0)
				(type default)
			)
			(fill no)
			(layer "B.CrtYd")
		)
		(fp_poly
			(pts
				(arc
					(start 0.889 0)
					(mid -0.889 0)
					(end 0.889 0)
				)
			)
			(stroke
				(width 0)
				(type default)
			)
			(fill no)
			(layer "F.CrtYd")
		)
		(pad "1" thru_hole circle
			(at 0 0)
			(size 0.508 0.508)
			(drill 0.254)
			(layers "*.Cu" "*.Mask")
			(remove_unused_layers no)
			(net "CLK_125M_OE")
			(clearance 0.1016)
			(padstack
				(mode front_inner_back)
				(layer "Inner"
					(shape circle)
					(size 0.508 0.508)
					(clearance 0.1016)
				)
				(layer "B.Cu"
					(shape circle)
					(size 0.762 0.762)
					(clearance -0.0254)
				)
			)
		)
	)
	(footprint ""
		(layer "F.Cu")
		(at 146.6088 -17.2466 -90)
		(property "Reference" "C227"
			(at 1.79197 -2.6162 0)
			(unlocked yes)
			(layer "F.SilkS")
			(effects
				(font
					(size 0.7874 0.5842)
					(thickness 0.1524)
				)
			)
		)
		(property "Value" "VAL*"
			(at 0.0762 2.067306 270)
			(unlocked yes)
			(layer "F.Fab")
			(hide yes)
			(effects
				(font
					(size 0.7874 0.5842)
					(thickness 0.1524)
				)
			)
		)
		(property "Tolerance" "TOL*"
			(at 0.0762 3.032506 270)
			(unlocked yes)
			(layer "Cmts.User")
			(hide yes)
			(effects
				(font
					(size 0.7874 0.5842)
					(thickness 0.1524)
				)
			)
		)
		(property "User Part Number" "PARTNUM*"
			(at 0.1016 4.023106 270)
			(unlocked yes)
			(layer "Cmts.User")
			(hide yes)
			(effects
				(font
					(size 0.7874 0.5842)
					(thickness 0.1524)
				)
			)
		)
		(property "Device Type" "CAPACITOR-G105-0B104-EK,0.1UF,A"
			(at 0.0508 1.127506 270)
			(unlocked yes)
			(layer "F.Fab")
			(hide yes)
			(effects
				(font
					(size 0.7874 0.5842)
					(thickness 0.1524)
				)
			)
		)
		(duplicate_pad_numbers_are_jumpers no)
		(fp_line
			(start -1.143 0.5588)
			(end 1.143 0.5588)
			(stroke
				(width 0.1)
				(type default)
			)
			(layer "F.SilkS")
		)
		(fp_line
			(start 1.143 0.5588)
			(end 1.143 -0.5588)
			(stroke
				(width 0.1)
				(type default)
			)
			(layer "F.SilkS")
		)
		(fp_line
			(start -1.143 -0.5588)
			(end -1.143 0.5588)
			(stroke
				(width 0.1)
				(type default)
			)
			(layer "F.SilkS")
		)
		(fp_line
			(start 1.143 -0.5588)
			(end -1.143 -0.5588)
			(stroke
				(width 0.1)
				(type default)
			)
			(layer "F.SilkS")
		)
		(fp_rect
			(start -1.143 -0.5588)
			(end 1.143 0.5588)
			(stroke
				(width 0)
				(type default)
			)
			(fill no)
			(layer "F.CrtYd")
		)
		(fp_line
			(start -0.508 0.3048)
			(end 0.508 0.3048)
			(stroke
				(width 0.1)
				(type default)
			)
			(layer "F.Fab")
		)
		(fp_line
			(start 0.508 0.3048)
			(end 0.508 -0.3048)
			(stroke
				(width 0.1)
				(type default)
			)
			(layer "F.Fab")
		)
		(fp_line
			(start -0.508 -0.3048)
			(end -0.508 0.3048)
			(stroke
				(width 0.1)
				(type default)
			)
			(layer "F.Fab")
		)
		(fp_line
			(start 0.508 -0.3048)
			(end -0.508 -0.3048)
			(stroke
				(width 0.1)
				(type default)
			)
			(layer "F.Fab")
		)
		(pad "1" smd rect
			(at -0.5334 0 270)
			(size 0.7112 0.6096)
			(layers "F.Cu" "F.Mask" "F.Paste")
			(net "UNNAMED_515_CAPACITOR_I128_1")
		)
		(pad "2" smd rect
			(at 0.5334 0 270)
			(size 0.7112 0.6096)
			(layers "F.Cu" "F.Mask" "F.Paste")
			(net "SG")
		)
		(zone
			(layer "F.Cu")
			(hatch none 0.5)
			(connect_pads
				(clearance 0)
			)
			(min_thickness 0.25)
			(keepout
				(tracks allowed)
				(vias not_allowed)
				(pads allowed)
				(copperpour not_allowed)
				(footprints allowed)
			)
			(placement
				(enabled no)
				(sheetname "")
			)
			(fill
				(thermal_gap 0.5)
				(thermal_bridge_width 0.5)
				(island_removal_mode 0)
			)
			(polygon
				(pts
					(xy 146.9136 -17.3228) (xy 146.304 -17.3228) (xy 146.304 -17.1704) (xy 146.9136 -17.1704)
				)
			)
		)
	)
)
